(kicad_pcb
	(version 20260206)
	(generator "pcbnew")
	(generator_version "10.0")
	(general
		(thickness 1.6)
		(legacy_teardrops no)
	)
	(paper "A4")
	(title_block
		(title "03242023_DA0F0TMBIJ0_F0T_Motherboard_J_brd_V01_OCP.brd")
		(comment 1 "Grand Teton / footprints 2422-2428 of 6105")
	)
	(layers
		(0 "F.Cu" signal "TOP")
		(4 "In1.Cu" signal "GND")
		(6 "In2.Cu" signal "IN1")
		(8 "In3.Cu" signal "GND1")
		(10 "In4.Cu" signal "IN2")
		(12 "In5.Cu" signal "GND2")
		(14 "In6.Cu" signal "IN3")
		(16 "In7.Cu" signal "GND3")
		(18 "In8.Cu" signal "VCC")
		(20 "In9.Cu" signal "VCC1")
		(22 "In10.Cu" signal "GND4")
		(24 "In11.Cu" signal "IN4")
		(26 "In12.Cu" signal "GND5")
		(28 "In13.Cu" signal "IN5")
		(30 "In14.Cu" signal "GND6")
		(32 "In15.Cu" signal "IN6")
		(34 "In16.Cu" signal "GND7")
		(2 "B.Cu" signal "BOTTOM")
		(9 "F.Adhes" user "F.Adhesive")
		(11 "B.Adhes" user "B.Adhesive")
		(13 "F.Paste" user "Package Geometry/Pastemask Top")
		(15 "B.Paste" user "Package Geometry/Pastemask Bottom")
		(5 "F.SilkS" user "Ref Des/Silkscreen Top")
		(7 "B.SilkS" user "Ref Des/Silkscreen Bottom")
		(1 "F.Mask" user "Board Geometry/Soldermask Top")
		(3 "B.Mask" user "Board Geometry/Soldermask Bottom")
		(17 "Dwgs.User" user "User.Drawings")
		(19 "Cmts.User" user "User.Comments")
		(21 "Eco1.User" user "User.Eco1")
		(23 "Eco2.User" user "User.Eco2")
		(25 "Edge.Cuts" user "Board Geometry/Outline")
		(27 "Margin" user)
		(31 "F.CrtYd" user "Package Geometry/Place Bound Top")
		(29 "B.CrtYd" user "Package Geometry/Place Bound Bottom")
		(35 "F.Fab" user "Ref Des/Assembly Top")
		(33 "B.Fab" user "Ref Des/Assembly Bottom")
	)
	(footprint ""
		(layer "F.Cu")
		(at 290.874704 -372.471188)
		(property "Reference" "PL44"
			(at -1.46812 -4.415028 0)
			(unlocked yes)
			(layer "F.SilkS")
			(effects
				(font
					(size 0.7874 0.5842)
					(thickness 0.1524)
				)
				(justify left)
			)
		)
		(property "Value" ""
			(at 0 0 0)
			(layer "F.Fab")
			(effects
				(font
					(size 1.27 1.27)
				)
			)
		)
		(duplicate_pad_numbers_are_jumpers no)
		(fp_line
			(start -2.249932 -2.249932)
			(end 2.249932 -2.249932)
			(stroke
				(width 0.1524)
				(type default)
			)
			(layer "F.SilkS")
		)
		(fp_line
			(start -2.249932 -1.3843)
			(end -2.249932 -2.249932)
			(stroke
				(width 0.1524)
				(type default)
			)
			(layer "F.SilkS")
		)
		(fp_line
			(start -2.249932 2.249932)
			(end -2.249932 1.3843)
			(stroke
				(width 0.1524)
				(type default)
			)
			(layer "F.SilkS")
		)
		(fp_line
			(start 2.249932 -2.249932)
			(end 2.249932 -1.3843)
			(stroke
				(width 0.1524)
				(type default)
			)
			(layer "F.SilkS")
		)
		(fp_line
			(start 2.249932 1.3843)
			(end 2.249932 2.249932)
			(stroke
				(width 0.1524)
				(type default)
			)
			(layer "F.SilkS")
		)
		(fp_line
			(start 2.249932 2.249932)
			(end -2.249932 2.249932)
			(stroke
				(width 0.1524)
				(type default)
			)
			(layer "F.SilkS")
		)
		(fp_line
			(start -2.249932 -2.249932)
			(end 2.249932 -2.249932)
			(stroke
				(width 0.1)
				(type default)
			)
			(layer "F.Fab")
		)
		(fp_line
			(start -2.249932 2.249932)
			(end -2.249932 -2.249932)
			(stroke
				(width 0.1)
				(type default)
			)
			(layer "F.Fab")
		)
		(fp_line
			(start 2.249932 -2.249932)
			(end 2.249932 2.249932)
			(stroke
				(width 0.1)
				(type default)
			)
			(layer "F.Fab")
		)
		(fp_line
			(start 2.249932 2.249932)
			(end -2.249932 2.249932)
			(stroke
				(width 0.1)
				(type default)
			)
			(layer "F.Fab")
		)
		(pad "1" smd rect
			(at -1.82499 0)
			(size 1.0668 2.5146)
			(layers "F.Cu" "F.Mask" "F.Paste")
			(net "P12V_AUX")
		)
		(pad "2" smd rect
			(at 1.82499 0)
			(size 1.0668 2.5146)
			(layers "F.Cu" "F.Mask" "F.Paste")
			(net "SW_P12V_PVCCFA_EHV_FIVRA_CPU0_L")
		)
	)
	(footprint ""
		(layer "F.Cu")
		(at 372.561358 -92.962984 90)
		(property "Reference" "R481"
			(at 0 0 90)
			(layer "F.SilkS")
			(hide yes)
			(effects
				(font
					(size 1.27 1.27)
				)
			)
		)
		(property "Value" ""
			(at 0 0 90)
			(layer "F.Fab")
			(effects
				(font
					(size 1.27 1.27)
				)
			)
		)
		(duplicate_pad_numbers_are_jumpers no)
		(fp_line
			(start 0.7874 -0.4064)
			(end 0.7874 0.4064)
			(stroke
				(width 0.1524)
				(type default)
			)
			(layer "F.SilkS")
		)
		(fp_line
			(start -0.7874 -0.4064)
			(end 0.7874 -0.4064)
			(stroke
				(width 0.1524)
				(type default)
			)
			(layer "F.SilkS")
		)
		(fp_line
			(start 0.7874 0.4064)
			(end -0.7874 0.4064)
			(stroke
				(width 0.1524)
				(type default)
			)
			(layer "F.SilkS")
		)
		(fp_line
			(start -0.7874 0.4064)
			(end -0.7874 -0.4064)
			(stroke
				(width 0.1524)
				(type default)
			)
			(layer "F.SilkS")
		)
		(fp_line
			(start -0.12065 -0.305054)
			(end -0.12065 -0.2794)
			(stroke
				(width 0.1)
				(type default)
			)
			(layer "F.Fab")
		)
		(fp_line
			(start -0.67945 -0.305054)
			(end -0.12065 -0.305054)
			(stroke
				(width 0.1)
				(type default)
			)
			(layer "F.Fab")
		)
		(fp_line
			(start 0.67945 -0.3048)
			(end 0.67945 0.3048)
			(stroke
				(width 0.1)
				(type default)
			)
			(layer "F.Fab")
		)
		(fp_line
			(start 0.12065 -0.3048)
			(end 0.67945 -0.3048)
			(stroke
				(width 0.1)
				(type default)
			)
			(layer "F.Fab")
		)
		(fp_line
			(start 0.12065 -0.2794)
			(end 0.12065 -0.3048)
			(stroke
				(width 0.1)
				(type default)
			)
			(layer "F.Fab")
		)
		(fp_line
			(start -0.12065 -0.2794)
			(end 0.12065 -0.2794)
			(stroke
				(width 0.1)
				(type default)
			)
			(layer "F.Fab")
		)
		(fp_line
			(start 0.120396 0.2794)
			(end -0.12065 0.2794)
			(stroke
				(width 0.1)
				(type default)
			)
			(layer "F.Fab")
		)
		(fp_line
			(start -0.12065 0.2794)
			(end -0.12065 0.3048)
			(stroke
				(width 0.1)
				(type default)
			)
			(layer "F.Fab")
		)
		(fp_line
			(start 0.67945 0.3048)
			(end 0.120396 0.3048)
			(stroke
				(width 0.1)
				(type default)
			)
			(layer "F.Fab")
		)
		(fp_line
			(start 0.120396 0.3048)
			(end 0.120396 0.2794)
			(stroke
				(width 0.1)
				(type default)
			)
			(layer "F.Fab")
		)
		(fp_line
			(start -0.12065 0.3048)
			(end -0.67945 0.3048)
			(stroke
				(width 0.1)
				(type default)
			)
			(layer "F.Fab")
		)
		(fp_line
			(start -0.67945 0.3048)
			(end -0.67945 -0.305054)
			(stroke
				(width 0.1)
				(type default)
			)
			(layer "F.Fab")
		)
		(pad "1" smd circle
			(at -0.40005 0 90)
			(size 0 0)
			(layers "F.Cu" "F.Mask" "F.Paste")
			(net "JTAG_DBP_TDI")
		)
		(pad "2" smd circle
			(at 0.40005 0 90)
			(size 0 0)
			(layers "F.Cu" "F.Mask" "F.Paste")
			(net "JTAG_DBP_FB_TDI")
		)
	)
	(footprint ""
		(layer "F.Cu")
		(at 223.384364 -75.86091 180)
		(property "Reference" "PR4527"
			(at 0 0 180)
			(layer "F.SilkS")
			(hide yes)
			(effects
				(font
					(size 1.27 1.27)
				)
			)
		)
		(property "Value" ""
			(at 0 0 180)
			(layer "F.Fab")
			(effects
				(font
					(size 1.27 1.27)
				)
			)
		)
		(duplicate_pad_numbers_are_jumpers no)
		(fp_line
			(start 0.7874 0.4064)
			(end -0.7874 0.4064)
			(stroke
				(width 0.1524)
				(type default)
			)
			(layer "F.SilkS")
		)
		(fp_line
			(start 0.7874 -0.4064)
			(end 0.7874 0.4064)
			(stroke
				(width 0.1524)
				(type default)
			)
			(layer "F.SilkS")
		)
		(fp_line
			(start -0.7874 0.4064)
			(end -0.7874 -0.4064)
			(stroke
				(width 0.1524)
				(type default)
			)
			(layer "F.SilkS")
		)
		(fp_line
			(start -0.7874 -0.4064)
			(end 0.7874 -0.4064)
			(stroke
				(width 0.1524)
				(type default)
			)
			(layer "F.SilkS")
		)
		(fp_line
			(start 0.67945 0.3048)
			(end 0.120396 0.3048)
			(stroke
				(width 0.1)
				(type default)
			)
			(layer "F.Fab")
		)
		(fp_line
			(start 0.67945 -0.3048)
			(end 0.67945 0.3048)
			(stroke
				(width 0.1)
				(type default)
			)
			(layer "F.Fab")
		)
		(fp_line
			(start 0.12065 -0.2794)
			(end 0.12065 -0.3048)
			(stroke
				(width 0.1)
				(type default)
			)
			(layer "F.Fab")
		)
		(fp_line
			(start 0.12065 -0.3048)
			(end 0.67945 -0.3048)
			(stroke
				(width 0.1)
				(type default)
			)
			(layer "F.Fab")
		)
		(fp_line
			(start 0.120396 0.3048)
			(end 0.120396 0.2794)
			(stroke
				(width 0.1)
				(type default)
			)
			(layer "F.Fab")
		)
		(fp_line
			(start 0.120396 0.2794)
			(end -0.12065 0.2794)
			(stroke
				(width 0.1)
				(type default)
			)
			(layer "F.Fab")
		)
		(fp_line
			(start -0.12065 0.3048)
			(end -0.67945 0.3048)
			(stroke
				(width 0.1)
				(type default)
			)
			(layer "F.Fab")
		)
		(fp_line
			(start -0.12065 0.2794)
			(end -0.12065 0.3048)
			(stroke
				(width 0.1)
				(type default)
			)
			(layer "F.Fab")
		)
		(fp_line
			(start -0.12065 -0.2794)
			(end 0.12065 -0.2794)
			(stroke
				(width 0.1)
				(type default)
			)
			(layer "F.Fab")
		)
		(fp_line
			(start -0.12065 -0.305054)
			(end -0.12065 -0.2794)
			(stroke
				(width 0.1)
				(type default)
			)
			(layer "F.Fab")
		)
		(fp_line
			(start -0.67945 0.3048)
			(end -0.67945 -0.305054)
			(stroke
				(width 0.1)
				(type default)
			)
			(layer "F.Fab")
		)
		(fp_line
			(start -0.67945 -0.305054)
			(end -0.12065 -0.305054)
			(stroke
				(width 0.1)
				(type default)
			)
			(layer "F.Fab")
		)
		(pad "1" smd circle
			(at -0.40005 0 180)
			(size 0 0)
			(layers "F.Cu" "F.Mask" "F.Paste")
			(net "P3V3_E1S_0_R")
		)
		(pad "2" smd circle
			(at 0.40005 0 180)
			(size 0 0)
			(layers "F.Cu" "F.Mask" "F.Paste")
			(net "P3V3_E1S_GATE_0")
		)
	)
	(footprint ""
		(layer "F.Cu")
		(at 318.468248 -408.517344 -90)
		(property "Reference" "C911"
			(at 0 0 270)
			(layer "F.SilkS")
			(hide yes)
			(effects
				(font
					(size 1.27 1.27)
				)
			)
		)
		(property "Value" ""
			(at 0 0 270)
			(layer "F.Fab")
			(effects
				(font
					(size 1.27 1.27)
				)
			)
		)
		(duplicate_pad_numbers_are_jumpers no)
		(fp_line
			(start -0.299974 0.150114)
			(end -0.299974 -0.150114)
			(stroke
				(width 0.1)
				(type default)
			)
			(layer "F.Fab")
		)
		(fp_line
			(start 0.299974 0.150114)
			(end -0.299974 0.150114)
			(stroke
				(width 0.1)
				(type default)
			)
			(layer "F.Fab")
		)
		(fp_line
			(start -0.299974 -0.150114)
			(end 0.299974 -0.150114)
			(stroke
				(width 0.1)
				(type default)
			)
			(layer "F.Fab")
		)
		(fp_line
			(start 0.299974 -0.150114)
			(end 0.299974 0.150114)
			(stroke
				(width 0.1)
				(type default)
			)
			(layer "F.Fab")
		)
		(pad "1" smd rect
			(at -0.2667 0 270)
			(size 0.3048 0.381)
			(layers "F.Cu" "F.Mask" "F.Paste")
			(net "P5E_CPU0_PE0_TX_C_DP<11>")
		)
		(pad "2" smd rect
			(at 0.2667 0 270)
			(size 0.3048 0.381)
			(layers "F.Cu" "F.Mask" "F.Paste")
			(net "P5E_CPU0_PE0_TX_DP<11>")
		)
	)
	(footprint ""
		(layer "F.Cu")
		(at 48.28794 -145.026888 -90)
		(property "Reference" "PC1659"
			(at 0 0 270)
			(layer "F.SilkS")
			(hide yes)
			(effects
				(font
					(size 1.27 1.27)
				)
			)
		)
		(property "Value" ""
			(at 0 0 270)
			(layer "F.Fab")
			(effects
				(font
					(size 1.27 1.27)
				)
			)
		)
		(duplicate_pad_numbers_are_jumpers no)
		(fp_line
			(start -0.7874 0.4064)
			(end -0.7874 -0.4064)
			(stroke
				(width 0.1524)
				(type default)
			)
			(layer "F.SilkS")
		)
		(fp_line
			(start 0.7874 0.4064)
			(end -0.7874 0.4064)
			(stroke
				(width 0.1524)
				(type default)
			)
			(layer "F.SilkS")
		)
		(fp_line
			(start -0.7874 -0.4064)
			(end 0.7874 -0.4064)
			(stroke
				(width 0.1524)
				(type default)
			)
			(layer "F.SilkS")
		)
		(fp_line
			(start 0.7874 -0.4064)
			(end 0.7874 0.4064)
			(stroke
				(width 0.1524)
				(type default)
			)
			(layer "F.SilkS")
		)
		(fp_line
			(start -0.67945 0.3048)
			(end -0.67945 -0.305054)
			(stroke
				(width 0.1)
				(type default)
			)
			(layer "F.Fab")
		)
		(fp_line
			(start -0.12065 0.3048)
			(end -0.67945 0.3048)
			(stroke
				(width 0.1)
				(type default)
			)
			(layer "F.Fab")
		)
		(fp_line
			(start 0.120396 0.3048)
			(end 0.120396 0.2794)
			(stroke
				(width 0.1)
				(type default)
			)
			(layer "F.Fab")
		)
		(fp_line
			(start 0.67945 0.3048)
			(end 0.120396 0.3048)
			(stroke
				(width 0.1)
				(type default)
			)
			(layer "F.Fab")
		)
		(fp_line
			(start -0.12065 0.2794)
			(end -0.12065 0.3048)
			(stroke
				(width 0.1)
				(type default)
			)
			(layer "F.Fab")
		)
		(fp_line
			(start 0.120396 0.2794)
			(end -0.12065 0.2794)
			(stroke
				(width 0.1)
				(type default)
			)
			(layer "F.Fab")
		)
		(fp_line
			(start -0.12065 -0.2794)
			(end 0.12065 -0.2794)
			(stroke
				(width 0.1)
				(type default)
			)
			(layer "F.Fab")
		)
		(fp_line
			(start 0.12065 -0.2794)
			(end 0.12065 -0.3048)
			(stroke
				(width 0.1)
				(type default)
			)
			(layer "F.Fab")
		)
		(fp_line
			(start 0.12065 -0.3048)
			(end 0.67945 -0.3048)
			(stroke
				(width 0.1)
				(type default)
			)
			(layer "F.Fab")
		)
		(fp_line
			(start 0.67945 -0.3048)
			(end 0.67945 0.3048)
			(stroke
				(width 0.1)
				(type default)
			)
			(layer "F.Fab")
		)
		(fp_line
			(start -0.67945 -0.305054)
			(end -0.12065 -0.305054)
			(stroke
				(width 0.1)
				(type default)
			)
			(layer "F.Fab")
		)
		(fp_line
			(start -0.12065 -0.305054)
			(end -0.12065 -0.2794)
			(stroke
				(width 0.1)
				(type default)
			)
			(layer "F.Fab")
		)
		(pad "1" smd circle
			(at -0.40005 0 270)
			(size 0 0)
			(layers "F.Cu" "F.Mask" "F.Paste")
			(net "P12V_AUX")
		)
		(pad "2" smd circle
			(at 0.40005 0 270)
			(size 0 0)
			(layers "F.Cu" "F.Mask" "F.Paste")
			(net "GND")
		)
	)
	(footprint ""
		(layer "F.Cu")
		(at 191.806322 -20.126452 180)
		(property "Reference" "PD116"
			(at 10.696702 -0.955294 0)
			(unlocked yes)
			(layer "F.SilkS")
			(effects
				(font
					(size 0.7874 0.5842)
					(thickness 0.1524)
				)
				(justify left)
			)
		)
		(property "Value" ""
			(at 0 0 180)
			(layer "F.Fab")
			(effects
				(font
					(size 1.27 1.27)
				)
			)
		)
		(duplicate_pad_numbers_are_jumpers no)
		(fp_line
			(start 4.107942 1.459992)
			(end -3.400044 1.459992)
			(stroke
				(width 0.1524)
				(type default)
			)
			(layer "F.SilkS")
		)
		(fp_line
			(start 4.107942 -1.459992)
			(end 4.107942 1.459992)
			(stroke
				(width 0.1524)
				(type default)
			)
			(layer "F.SilkS")
		)
		(fp_line
			(start -3.400044 1.459992)
			(end -3.400044 -1.459992)
			(stroke
				(width 0.1524)
				(type default)
			)
			(layer "F.SilkS")
		)
		(fp_line
			(start -3.400044 -1.459992)
			(end 4.107942 -1.459992)
			(stroke
				(width 0.1524)
				(type default)
			)
			(layer "F.SilkS")
		)
		(fp_rect
			(start 4.107942 -1.459992)
			(end 3.308096 1.459992)
			(stroke
				(width 0)
				(type default)
			)
			(fill yes)
			(layer "F.SilkS")
		)
		(fp_line
			(start 2.29997 1.459992)
			(end -2.29997 1.459992)
			(stroke
				(width 0.1)
				(type default)
			)
			(layer "F.Fab")
		)
		(fp_line
			(start 2.29997 -1.459992)
			(end 2.29997 1.459992)
			(stroke
				(width 0.1)
				(type default)
			)
			(layer "F.Fab")
		)
		(fp_line
			(start -2.29997 1.459992)
			(end -2.29997 -1.459992)
			(stroke
				(width 0.1)
				(type default)
			)
			(layer "F.Fab")
		)
		(fp_line
			(start -2.29997 -1.459992)
			(end 2.29997 -1.459992)
			(stroke
				(width 0.1)
				(type default)
			)
			(layer "F.Fab")
		)
		(fp_text user "-"
			(at 5.4102 0.29845 0)
			(unlocked yes)
			(layer "F.SilkS")
			(effects
				(font
					(size 1.905 1.4224)
					(thickness 0.1524)
				)
				(justify left)
			)
		)
		(fp_text user "+"
			(at -4.7752 -0.12065 180)
			(unlocked yes)
			(layer "F.SilkS")
			(effects
				(font
					(size 1.905 1.4224)
					(thickness 0.1524)
				)
				(justify left)
			)
		)
		(fp_text user "-"
			(at 5.4102 0.29845 0)
			(unlocked yes)
			(layer "F.Fab")
			(effects
				(font
					(size 1.905 1.4224)
					(thickness 0.1524)
				)
				(justify left)
			)
		)
		(fp_text user "+"
			(at -4.7752 -0.12065 180)
			(unlocked yes)
			(layer "F.Fab")
			(effects
				(font
					(size 1.905 1.4224)
					(thickness 0.1524)
				)
				(justify left)
			)
		)
		(pad "A" smd rect
			(at -1.999996 0 270)
			(size 1.7018 2.5146)
			(layers "F.Cu" "F.Mask" "F.Paste")
			(net "GND")
		)
		(pad "C" smd rect
			(at 1.999996 0 270)
			(size 1.7018 2.5146)
			(layers "F.Cu" "F.Mask" "F.Paste")
			(net "P12V_SCM_R")
		)
	)
	(footprint ""
		(layer "F.Cu")
		(at 401.62988 -186.781948)
		(property "Reference" "R323"
			(at 0 0 0)
			(layer "F.SilkS")
			(hide yes)
			(effects
				(font
					(size 1.27 1.27)
				)
			)
		)
		(property "Value" ""
			(at 0 0 0)
			(layer "F.Fab")
			(effects
				(font
					(size 1.27 1.27)
				)
			)
		)
		(duplicate_pad_numbers_are_jumpers no)
		(fp_line
			(start -2.044192 -0.94361)
			(end -2.044192 0.898398)
			(stroke
				(width 0.1524)
				(type default)
			)
			(layer "F.SilkS")
		)
		(fp_line
			(start -2.044192 0.94361)
			(end 2.044192 0.94361)
			(stroke
				(width 0.1524)
				(type default)
			)
			(layer "F.SilkS")
		)
		(fp_line
			(start 2.044192 -0.94361)
			(end -2.044192 -0.94361)
			(stroke
				(width 0.1524)
				(type default)
			)
			(layer "F.SilkS")
		)
		(fp_line
			(start 2.044192 0.94361)
			(end 2.044192 -0.94361)
			(stroke
				(width 0.1524)
				(type default)
			)
			(layer "F.SilkS")
		)
		(fp_line
			(start -1.625092 -0.87503)
			(end -1.625092 0.87503)
			(stroke
				(width 0.1)
				(type default)
			)
			(layer "F.Fab")
		)
		(fp_line
			(start -1.625092 0.87503)
			(end 1.625092 0.87503)
			(stroke
				(width 0.1)
				(type default)
			)
			(layer "F.Fab")
		)
		(fp_line
			(start 1.625092 -0.87503)
			(end -1.625092 -0.87503)
			(stroke
				(width 0.1)
				(type default)
			)
			(layer "F.Fab")
		)
		(fp_line
			(start 1.625092 0.87503)
			(end 1.625092 -0.87503)
			(stroke
				(width 0.1)
				(type default)
			)
			(layer "F.Fab")
		)
		(pad "1" smd rect
			(at -1.450086 0)
			(size 0.9144 1.6002)
			(layers "F.Cu" "F.Mask" "F.Paste")
			(net "PVCCINFAON_CPU0")
		)
		(pad "2" smd rect
			(at 1.450086 0)
			(size 0.9144 1.6002)
			(layers "F.Cu" "F.Mask" "F.Paste")
			(net "PVNN_TERM_CPU0")
		)
	)
)
